(kicad_pcb
	(version 20260206)
	(generator "pcbnew")
	(generator_version "10.0")
	(general
		(thickness 1.6)
		(legacy_teardrops no)
	)
	(paper "A4")
	(title_block
		(title "Bryce Canyon_R.DPB_16317-1_OCP.brd")
		(comment 1 "Bryce Canyon / footprints 125-131 of 2099")
	)
	(layers
		(0 "F.Cu" signal "TOP")
		(4 "In1.Cu" signal "L2GND")
		(6 "In2.Cu" signal "L3")
		(8 "In3.Cu" signal "L4VCC")
		(10 "In4.Cu" signal "L5VCC")
		(12 "In5.Cu" signal "L6")
		(14 "In6.Cu" signal "L7GND")
		(2 "B.Cu" signal "BOTTOM")
		(9 "F.Adhes" user "F.Adhesive")
		(11 "B.Adhes" user "B.Adhesive")
		(13 "F.Paste" user "Package Geometry/Pastemask Top")
		(15 "B.Paste" user "Package Geometry/Pastemask Bottom")
		(5 "F.SilkS" user "Ref Des/Silkscreen Top")
		(7 "B.SilkS" user "Ref Des/Silkscreen Bottom")
		(1 "F.Mask" user "Board Geometry/Soldermask Top")
		(3 "B.Mask" user "Board Geometry/Soldermask Bottom")
		(17 "Dwgs.User" user "User.Drawings")
		(19 "Cmts.User" user "User.Comments")
		(21 "Eco1.User" user "User.Eco1")
		(23 "Eco2.User" user "User.Eco2")
		(25 "Edge.Cuts" user "Board Geometry/Outline")
		(27 "Margin" user)
		(31 "F.CrtYd" user "Package Geometry/Place Bound Top")
		(29 "B.CrtYd" user "Package Geometry/Place Bound Bottom")
		(35 "F.Fab" user "Ref Des/Assembly Top")
		(33 "B.Fab" user "Ref Des/Assembly Bottom")
	)
	(footprint ""
		(layer "F.Cu")
		(at 186.748928 -367.114836)
		(property "Reference" "C711"
			(at 0 0 0)
			(layer "F.SilkS")
			(hide yes)
			(effects
				(font
					(size 1.27 1.27)
				)
			)
		)
		(property "Value" "SCD1U16V2KX-3GP"
			(at 1.1811 -2.7051 0)
			(unlocked yes)
			(layer "F.Fab")
			(hide yes)
			(effects
				(font
					(size 1.016 1.016)
					(thickness 0.1524)
				)
			)
		)
		(property "Device Type" "C402H22"
			(at 1.1811 -4.2291 0)
			(unlocked yes)
			(layer "F.Fab")
			(hide yes)
			(effects
				(font
					(size 1.016 1.016)
					(thickness 0.1524)
				)
			)
		)
		(duplicate_pad_numbers_are_jumpers no)
		(fp_rect
			(start -0.4318 0.9525)
			(end 0.4318 -0.9525)
			(stroke
				(width 0)
				(type default)
			)
			(fill no)
			(layer "F.CrtYd")
		)
		(fp_rect
			(start -0.4318 0.9525)
			(end 0.4318 -0.9525)
			(stroke
				(width 0)
				(type default)
			)
			(fill no)
			(layer "F.Fab")
		)
		(pad "1" smd custom
			(at 0 -0.4445)
			(size 0.1524 0.1524)
			(layers "F.Cu" "F.Mask" "F.Paste")
			(net "P3V3_IN")
			(options
				(clearance outline)
				(anchor circle)
			)
			(primitives
				(gr_poly
					(pts
						(arc
							(start 0.3048 -0.2032)
							(mid 0.275042 -0.275042)
							(end 0.2032 -0.3048)
						)
						(arc
							(start -0.2032 -0.3048)
							(mid -0.275042 -0.275042)
							(end -0.3048 -0.2032)
						)
						(arc
							(start -0.3048 0.2032)
							(mid -0.275042 0.275042)
							(end -0.2032 0.3048)
						)
						(arc
							(start 0.2032 0.3048)
							(mid 0.275042 0.275042)
							(end 0.3048 0.2032)
						)
					)
					(width 0)
					(fill yes)
				)
			)
		)
		(pad "2" smd custom
			(at 0 0.4445)
			(size 0.1524 0.1524)
			(layers "F.Cu" "F.Mask" "F.Paste")
			(net "GND")
			(options
				(clearance outline)
				(anchor circle)
			)
			(primitives
				(gr_poly
					(pts
						(arc
							(start 0.3048 -0.2032)
							(mid 0.275042 -0.275042)
							(end 0.2032 -0.3048)
						)
						(arc
							(start -0.2032 -0.3048)
							(mid -0.275042 -0.275042)
							(end -0.3048 -0.2032)
						)
						(arc
							(start -0.3048 0.2032)
							(mid -0.275042 0.275042)
							(end -0.2032 0.3048)
						)
						(arc
							(start 0.2032 0.3048)
							(mid 0.275042 0.275042)
							(end 0.3048 0.2032)
						)
					)
					(width 0)
					(fill yes)
				)
			)
		)
	)
	(footprint ""
		(layer "F.Cu")
		(at 332.867 -362.077 180)
		(property "Reference" "Q213"
			(at 0 0 180)
			(layer "F.SilkS")
			(hide yes)
			(effects
				(font
					(size 1.27 1.27)
				)
			)
		)
		(property "Value" "2N7002K-2-GP"
			(at 0.127 -8.9662 180)
			(unlocked yes)
			(layer "F.Fab")
			(hide yes)
			(effects
				(font
					(size 1.016 1.016)
					(thickness 0.1524)
				)
			)
		)
		(property "Device Type" "SOT23DGS2D4H44"
			(at 0.127 -10.4902 180)
			(unlocked yes)
			(layer "F.Fab")
			(hide yes)
			(effects
				(font
					(size 1.016 1.016)
					(thickness 0.1524)
				)
			)
		)
		(duplicate_pad_numbers_are_jumpers no)
		(fp_line
			(start 1.651 1.778)
			(end 1.651 -1.778)
			(stroke
				(width 0.1524)
				(type default)
			)
			(layer "F.SilkS")
		)
		(fp_line
			(start 1.651 -1.778)
			(end -1.651 -1.778)
			(stroke
				(width 0.1524)
				(type default)
			)
			(layer "F.SilkS")
		)
		(fp_line
			(start -1.651 1.778)
			(end 1.651 1.778)
			(stroke
				(width 0.1524)
				(type default)
			)
			(layer "F.SilkS")
		)
		(fp_line
			(start -1.651 -1.778)
			(end -1.651 1.778)
			(stroke
				(width 0.1524)
				(type default)
			)
			(layer "F.SilkS")
		)
		(fp_poly
			(pts
				(xy -1.778 1.8796) (xy -1.778 -1.8796) (xy 1.778 -1.8796) (xy 1.778 1.8796)
			)
			(stroke
				(width 0)
				(type default)
			)
			(fill no)
			(layer "F.CrtYd")
		)
		(fp_poly
			(pts
				(xy -1.778 1.8796) (xy -1.778 -1.8796) (xy 1.778 -1.8796) (xy 1.778 1.8796)
			)
			(stroke
				(width 0)
				(type default)
			)
			(fill no)
			(layer "F.Fab")
		)
		(pad "D" smd custom
			(at 0 -0.9525 180)
			(size 0.1905 0.1905)
			(layers "F.Cu" "F.Mask" "F.Paste")
			(net "GATE_FAN2")
			(options
				(clearance outline)
				(anchor circle)
			)
			(primitives
				(gr_poly
					(pts
						(arc
							(start -0.1778 0.5715)
							(mid -0.321484 0.511984)
							(end -0.381 0.3683)
						)
						(arc
							(start -0.381 -0.3683)
							(mid -0.321484 -0.511984)
							(end -0.1778 -0.5715)
						)
						(arc
							(start 0.1778 -0.5715)
							(mid 0.321484 -0.511984)
							(end 0.381 -0.3683)
						)
						(arc
							(start 0.381 0.3683)
							(mid 0.321484 0.511984)
							(end 0.1778 0.5715)
						)
					)
					(width 0)
					(fill yes)
				)
			)
		)
		(pad "G" smd custom
			(at -0.98425 0.9525 180)
			(size 0.1905 0.1905)
			(layers "F.Cu" "F.Mask" "F.Paste")
			(net "FAN_EN")
			(options
				(clearance outline)
				(anchor circle)
			)
			(primitives
				(gr_poly
					(pts
						(arc
							(start -0.1778 0.5715)
							(mid -0.321484 0.511984)
							(end -0.381 0.3683)
						)
						(arc
							(start -0.381 -0.3683)
							(mid -0.321484 -0.511984)
							(end -0.1778 -0.5715)
						)
						(arc
							(start 0.1778 -0.5715)
							(mid 0.321484 -0.511984)
							(end 0.381 -0.3683)
						)
						(arc
							(start 0.381 0.3683)
							(mid 0.321484 0.511984)
							(end 0.1778 0.5715)
						)
					)
					(width 0)
					(fill yes)
				)
			)
		)
		(pad "S" smd custom
			(at 0.98425 0.9525 180)
			(size 0.1905 0.1905)
			(layers "F.Cu" "F.Mask" "F.Paste")
			(net "GND")
			(options
				(clearance outline)
				(anchor circle)
			)
			(primitives
				(gr_poly
					(pts
						(arc
							(start -0.1778 0.5715)
							(mid -0.321484 0.511984)
							(end -0.381 0.3683)
						)
						(arc
							(start -0.381 -0.3683)
							(mid -0.321484 -0.511984)
							(end -0.1778 -0.5715)
						)
						(arc
							(start 0.1778 -0.5715)
							(mid 0.321484 -0.511984)
							(end 0.381 -0.3683)
						)
						(arc
							(start 0.381 0.3683)
							(mid 0.321484 0.511984)
							(end 0.1778 0.5715)
						)
					)
					(width 0)
					(fill yes)
				)
			)
		)
	)
	(footprint ""
		(layer "F.Cu")
		(at 140.97 -35.687 -90)
		(property "Reference" "C398"
			(at 0 0 270)
			(layer "F.SilkS")
			(hide yes)
			(effects
				(font
					(size 1.27 1.27)
				)
			)
		)
		(property "Value" "SC4D7U25V5KX-1-GP"
			(at -0.0762 -6.1214 270)
			(unlocked yes)
			(layer "F.Fab")
			(hide yes)
			(effects
				(font
					(size 1.016 1.016)
					(thickness 0.1524)
				)
			)
		)
		(property "Device Type" "C805H58"
			(at -0.0762 -8.1534 270)
			(unlocked yes)
			(layer "F.Fab")
			(hide yes)
			(effects
				(font
					(size 1.016 1.016)
					(thickness 0.1524)
				)
			)
		)
		(duplicate_pad_numbers_are_jumpers no)
		(fp_line
			(start 0.635 0)
			(end -0.635 0)
			(stroke
				(width 0.508)
				(type default)
			)
			(layer "F.SilkS")
		)
		(fp_rect
			(start -0.9652 1.778)
			(end 0.9652 -1.778)
			(stroke
				(width 0)
				(type default)
			)
			(fill no)
			(layer "F.CrtYd")
		)
		(fp_poly
			(pts
				(xy -0.9652 -1.778) (xy 0.9652 -1.778) (xy 0.9652 1.778) (xy -0.9652 1.778)
			)
			(stroke
				(width 0)
				(type default)
			)
			(fill no)
			(layer "F.Fab")
		)
		(pad "1" smd rect
			(at 0 -0.9652 270)
			(size 1.397 1.143)
			(layers "F.Cu" "F.Mask" "F.Paste")
			(net "P12V_HDD28")
		)
		(pad "2" smd rect
			(at 0 0.9652 270)
			(size 1.397 1.143)
			(layers "F.Cu" "F.Mask" "F.Paste")
			(net "GND")
		)
	)
	(footprint ""
		(layer "F.Cu")
		(at 461.01 -253.873 -90)
		(property "Reference" "Q38"
			(at 0 0 270)
			(layer "F.SilkS")
			(hide yes)
			(effects
				(font
					(size 1.27 1.27)
				)
			)
		)
		(property "Value" "AO4406AL-GP"
			(at -3.707384 -1.5367 270)
			(unlocked yes)
			(layer "F.Fab")
			(hide yes)
			(effects
				(font
					(size 1.016 1.016)
					(thickness 0.1524)
				)
			)
		)
		(property "Device Type" "SOIC8H69"
			(at -3.707384 -3.0607 270)
			(unlocked yes)
			(layer "F.Fab")
			(hide yes)
			(effects
				(font
					(size 1.016 1.016)
					(thickness 0.1524)
				)
			)
		)
		(duplicate_pad_numbers_are_jumpers no)
		(fp_line
			(start -2.6289 3.4417)
			(end -2.6289 1.4732)
			(stroke
				(width 0.381)
				(type default)
			)
			(layer "F.SilkS")
		)
		(fp_line
			(start -2.7432 1.4224)
			(end -2.6416 1.4224)
			(stroke
				(width 0.1524)
				(type default)
			)
			(layer "F.SilkS")
		)
		(fp_line
			(start -2.7432 1.4224)
			(end 2.1336 1.4224)
			(stroke
				(width 0.1524)
				(type default)
			)
			(layer "F.SilkS")
		)
		(fp_line
			(start 2.1336 1.4224)
			(end 2.1336 -1.4224)
			(stroke
				(width 0.1524)
				(type default)
			)
			(layer "F.SilkS")
		)
		(fp_line
			(start -2.1844 -0.0508)
			(end -2.7178 0.508)
			(stroke
				(width 0.1524)
				(type default)
			)
			(layer "F.SilkS")
		)
		(fp_line
			(start -2.7178 -0.508)
			(end -2.1844 -0.0508)
			(stroke
				(width 0.1524)
				(type default)
			)
			(layer "F.SilkS")
		)
		(fp_line
			(start -2.7432 -1.4224)
			(end -2.7432 1.4224)
			(stroke
				(width 0.1524)
				(type default)
			)
			(layer "F.SilkS")
		)
		(fp_line
			(start 2.1336 -1.4224)
			(end -2.7432 -1.4224)
			(stroke
				(width 0.1524)
				(type default)
			)
			(layer "F.SilkS")
		)
		(fp_poly
			(pts
				(xy -2.2098 -1.4224) (xy -2.2098 1.4224) (xy 2.2098 1.4224) (xy 2.2098 -1.4224)
			)
			(stroke
				(width 0)
				(type default)
			)
			(fill yes)
			(layer "F.SilkS")
		)
		(fp_rect
			(start -2.450084 2.999994)
			(end 2.450084 -2.999994)
			(stroke
				(width 0)
				(type default)
			)
			(fill no)
			(layer "F.CrtYd")
		)
		(fp_poly
			(pts
				(xy -2.8194 3.6322) (xy -2.8194 -3.6322) (xy 2.8194 -3.6322) (xy 2.8194 1.18364) (xy 2.450084 1.18364)
				(xy 2.450084 -2.999994) (xy -2.450084 -2.999994) (xy -2.450084 2.999994) (xy 2.450084 2.999994)
				(xy 2.450084 1.18618) (xy 2.8194 1.18618) (xy 2.8194 3.6322)
			)
			(stroke
				(width 0)
				(type default)
			)
			(fill no)
			(layer "F.CrtYd")
		)
		(fp_rect
			(start -2.8194 3.6322)
			(end 2.8194 -3.6322)
			(stroke
				(width 0)
				(type default)
			)
			(fill no)
			(layer "F.Fab")
		)
		(pad "1" smd rect
			(at -1.905 2.54 270)
			(size 0.635 1.651)
			(layers "F.Cu" "F.Mask" "F.Paste")
			(net "P5V_HDD10")
		)
		(pad "2" smd rect
			(at -0.635 2.54 270)
			(size 0.635 1.651)
			(layers "F.Cu" "F.Mask" "F.Paste")
			(net "P5V_HDD10")
		)
		(pad "3" smd rect
			(at 0.635 2.54 270)
			(size 0.635 1.651)
			(layers "F.Cu" "F.Mask" "F.Paste")
			(net "P5V_HDD10")
		)
		(pad "4" smd rect
			(at 1.905 2.54 270)
			(size 0.635 1.651)
			(layers "F.Cu" "F.Mask" "F.Paste")
			(net "SW_HDD_P10")
		)
		(pad "5" smd rect
			(at 1.905 -2.54 270)
			(size 0.635 1.651)
			(layers "F.Cu" "F.Mask" "F.Paste")
			(net "P5V_B_3")
		)
		(pad "6" smd rect
			(at 0.635 -2.54 270)
			(size 0.635 1.651)
			(layers "F.Cu" "F.Mask" "F.Paste")
			(net "P5V_B_3")
		)
		(pad "7" smd rect
			(at -0.635 -2.54 270)
			(size 0.635 1.651)
			(layers "F.Cu" "F.Mask" "F.Paste")
			(net "P5V_B_3")
		)
		(pad "8" smd rect
			(at -1.905 -2.54 270)
			(size 0.635 1.651)
			(layers "F.Cu" "F.Mask" "F.Paste")
			(net "P5V_B_3")
		)
	)
	(footprint ""
		(layer "F.Cu")
		(at 95.608902 -248.750074 -90)
		(property "Reference" "VIA6"
			(at 0 0 270)
			(layer "F.SilkS")
			(hide yes)
			(effects
				(font
					(size 1.27 1.27)
				)
			)
		)
		(property "Value" "100OHM-8L-2D36MM-L16-GP"
			(at -3.4036 -0.4572 270)
			(unlocked yes)
			(layer "F.Fab")
			(hide yes)
			(effects
				(font
					(size 1.016 1.016)
					(thickness 0.1524)
				)
			)
		)
		(property "Device Type" "VIA-PCIE-4P-427097"
			(at -3.4036 -1.9812 270)
			(unlocked yes)
			(layer "F.Fab")
			(hide yes)
			(effects
				(font
					(size 1.016 1.016)
					(thickness 0.1524)
				)
			)
		)
		(duplicate_pad_numbers_are_jumpers no)
		(fp_rect
			(start -2.1336 0.4826)
			(end 2.1336 -0.4826)
			(stroke
				(width 0)
				(type default)
			)
			(fill no)
			(layer "F.CrtYd")
		)
		(fp_rect
			(start -2.1336 0.4826)
			(end 2.1336 -0.4826)
			(stroke
				(width 0)
				(type default)
			)
			(fill no)
			(layer "F.Fab")
		)
		(pad "1" thru_hole circle
			(at -1.651 0 270)
			(size 0.508 0.508)
			(drill 0.254)
			(layers "*.Cu" "*.Mask")
			(remove_unused_layers no)
			(net "GND")
			(clearance 0.2286)
			(thermal_gap 0.2286)
		)
		(pad "2" thru_hole circle
			(at -0.635 0 270)
			(size 0.508 0.508)
			(drill 0.254)
			(layers "*.Cu" "*.Mask")
			(remove_unused_layers no)
			(net "PHY_DRV_B_TO_SCC_B_2_DP")
			(clearance 0.2286)
			(thermal_gap 0.2286)
		)
		(pad "3" thru_hole circle
			(at 0.635 0 270)
			(size 0.508 0.508)
			(drill 0.254)
			(layers "*.Cu" "*.Mask")
			(remove_unused_layers no)
			(net "PHY_DRV_B_TO_SCC_B_2_DN")
			(clearance 0.2286)
			(thermal_gap 0.2286)
		)
		(pad "4" thru_hole circle
			(at 1.651 0 270)
			(size 0.508 0.508)
			(drill 0.254)
			(layers "*.Cu" "*.Mask")
			(remove_unused_layers no)
			(net "GND")
			(clearance 0.2286)
			(thermal_gap 0.2286)
		)
	)
	(footprint ""
		(layer "F.Cu")
		(at 287.32861 -333.51978 180)
		(property "Reference" "C20"
			(at 0 0 180)
			(layer "F.SilkS")
			(hide yes)
			(effects
				(font
					(size 1.27 1.27)
				)
			)
		)
		(property "Value" "SC1U16V3KX-5GP"
			(at 0 -2.8194 180)
			(unlocked yes)
			(layer "F.Fab")
			(hide yes)
			(effects
				(font
					(size 1.016 1.016)
					(thickness 0.1524)
				)
			)
		)
		(property "Device Type" "C603H36"
			(at 0 -4.3434 180)
			(unlocked yes)
			(layer "F.Fab")
			(hide yes)
			(effects
				(font
					(size 1.016 1.016)
					(thickness 0.1524)
				)
			)
		)
		(duplicate_pad_numbers_are_jumpers no)
		(fp_line
			(start 0.508 0)
			(end -0.508 0)
			(stroke
				(width 0.2032)
				(type default)
			)
			(layer "F.SilkS")
		)
		(fp_rect
			(start -0.5842 1.3335)
			(end 0.5842 -1.3335)
			(stroke
				(width 0)
				(type default)
			)
			(fill no)
			(layer "F.CrtYd")
		)
		(fp_rect
			(start -0.5842 1.3335)
			(end 0.5842 -1.3335)
			(stroke
				(width 0)
				(type default)
			)
			(fill no)
			(layer "F.Fab")
		)
		(pad "1" smd custom
			(at 0 -0.762 180)
			(size 0.2159 0.2159)
			(layers "F.Cu" "F.Mask" "F.Paste")
			(net "P3V3_IN")
			(options
				(clearance outline)
				(anchor circle)
			)
			(primitives
				(gr_poly
					(pts
						(arc
							(start -0.3302 -0.4318)
							(mid -0.402042 -0.402042)
							(end -0.4318 -0.3302)
						)
						(arc
							(start -0.4318 0.3302)
							(mid -0.402042 0.402042)
							(end -0.3302 0.4318)
						)
						(arc
							(start 0.3302 0.4318)
							(mid 0.402042 0.402042)
							(end 0.4318 0.3302)
						)
						(arc
							(start 0.4318 -0.3302)
							(mid 0.402042 -0.402042)
							(end 0.3302 -0.4318)
						)
					)
					(width 0)
					(fill yes)
				)
			)
		)
		(pad "2" smd custom
			(at 0 0.762 180)
			(size 0.2159 0.2159)
			(layers "F.Cu" "F.Mask" "F.Paste")
			(net "GND")
			(options
				(clearance outline)
				(anchor circle)
			)
			(primitives
				(gr_poly
					(pts
						(arc
							(start -0.3302 -0.4318)
							(mid -0.402042 -0.402042)
							(end -0.4318 -0.3302)
						)
						(arc
							(start -0.4318 0.3302)
							(mid -0.402042 0.402042)
							(end -0.3302 0.4318)
						)
						(arc
							(start 0.3302 0.4318)
							(mid 0.402042 0.402042)
							(end 0.4318 0.3302)
						)
						(arc
							(start 0.4318 -0.3302)
							(mid 0.402042 -0.402042)
							(end 0.3302 -0.4318)
						)
					)
					(width 0)
					(fill yes)
				)
			)
		)
	)
	(footprint ""
		(layer "F.Cu")
		(at 454.168002 -230.96855 -90)
		(property "Reference" "R1148"
			(at 0 0 270)
			(layer "F.SilkS")
			(hide yes)
			(effects
				(font
					(size 1.27 1.27)
				)
			)
		)
		(property "Value" "143KR2F-L-1-GP"
			(at 0.064008 -3.993896 270)
			(unlocked yes)
			(layer "F.Fab")
			(hide yes)
			(effects
				(font
					(size 1.016 1.016)
					(thickness 0.1524)
				)
			)
		)
		(property "Device Type" "R402H16"
			(at 0.064008 -5.517896 270)
			(unlocked yes)
			(layer "F.Fab")
			(hide yes)
			(effects
				(font
					(size 1.016 1.016)
					(thickness 0.1524)
				)
			)
		)
		(duplicate_pad_numbers_are_jumpers no)
		(fp_line
			(start -0.508 -0.9398)
			(end -0.508 0.9398)
			(stroke
				(width 0.1524)
				(type default)
			)
			(layer "F.SilkS")
		)
		(fp_line
			(start 0.508 -0.9398)
			(end -0.508 -0.9398)
			(stroke
				(width 0.1524)
				(type default)
			)
			(layer "F.SilkS")
		)
		(fp_rect
			(start -0.508 0.9398)
			(end 0.508 -0.9398)
			(stroke
				(width 0)
				(type default)
			)
			(fill no)
			(layer "F.CrtYd")
		)
		(fp_rect
			(start -0.508 0.9398)
			(end 0.508 -0.9398)
			(stroke
				(width 0)
				(type default)
			)
			(fill no)
			(layer "F.Fab")
		)
		(pad "1" smd custom
			(at 0 -0.4445 270)
			(size 0.1397 0.1397)
			(layers "F.Cu" "F.Mask" "F.Paste")
			(net "AGND_P5V_B_3")
			(options
				(clearance outline)
				(anchor circle)
			)
			(primitives
				(gr_poly
					(pts
						(arc
							(start -0.1778 -0.2794)
							(mid -0.249642 -0.249642)
							(end -0.2794 -0.1778)
						)
						(arc
							(start -0.2794 0.1778)
							(mid -0.249642 0.249642)
							(end -0.1778 0.2794)
						)
						(arc
							(start 0.1778 0.2794)
							(mid 0.249642 0.249642)
							(end 0.2794 0.1778)
						)
						(arc
							(start 0.2794 -0.1778)
							(mid 0.249642 -0.249642)
							(end 0.1778 -0.2794)
						)
					)
					(width 0)
					(fill yes)
				)
			)
		)
		(pad "2" smd custom
			(at 0 0.4445 270)
			(size 0.1397 0.1397)
			(layers "F.Cu" "F.Mask" "F.Paste")
			(net "P5V_B_3_TRIP")
			(options
				(clearance outline)
				(anchor circle)
			)
			(primitives
				(gr_poly
					(pts
						(arc
							(start -0.1778 -0.2794)
							(mid -0.249642 -0.249642)
							(end -0.2794 -0.1778)
						)
						(arc
							(start -0.2794 0.1778)
							(mid -0.249642 0.249642)
							(end -0.1778 0.2794)
						)
						(arc
							(start 0.1778 0.2794)
							(mid 0.249642 0.249642)
							(end 0.2794 0.1778)
						)
						(arc
							(start 0.2794 -0.1778)
							(mid 0.249642 -0.249642)
							(end 0.1778 -0.2794)
						)
					)
					(width 0)
					(fill yes)
				)
			)
		)
	)
)
